(kicad_pcb
	(version 20260206)
	(generator "pcbnew")
	(generator_version "10.0")
	(general
		(thickness 1.6)
		(legacy_teardrops no)
	)
	(paper "A4")
	(title_block
		(title "9054_F0T_PDB_BD_GPU_F_V04_1213_1550_OCP.brd")
		(comment 1 "Grand Teton / footprints 603-605 of 608")
	)
	(layers
		(0 "F.Cu" signal "TOP")
		(4 "In1.Cu" signal "GND")
		(6 "In2.Cu" signal "IN1")
		(8 "In3.Cu" signal "GND1")
		(10 "In4.Cu" signal "VCC")
		(12 "In5.Cu" signal "VCC1")
		(14 "In6.Cu" signal "GND2")
		(16 "In7.Cu" signal "IN2")
		(18 "In8.Cu" signal "GND3")
		(2 "B.Cu" signal "BOTTOM")
		(9 "F.Adhes" user "F.Adhesive")
		(11 "B.Adhes" user "B.Adhesive")
		(13 "F.Paste" user "Package Geometry/Pastemask Top")
		(15 "B.Paste" user "Package Geometry/Pastemask Bottom")
		(5 "F.SilkS" user "Ref Des/Silkscreen Top")
		(7 "B.SilkS" user "Ref Des/Silkscreen Bottom")
		(1 "F.Mask" user "Board Geometry/Soldermask Top")
		(3 "B.Mask" user "Board Geometry/Soldermask Bottom")
		(17 "Dwgs.User" user "User.Drawings")
		(19 "Cmts.User" user "User.Comments")
		(21 "Eco1.User" user "User.Eco1")
		(23 "Eco2.User" user "User.Eco2")
		(25 "Edge.Cuts" user "Board Geometry/Outline")
		(27 "Margin" user)
		(31 "F.CrtYd" user "Package Geometry/Place Bound Top")
		(29 "B.CrtYd" user "Package Geometry/Place Bound Bottom")
		(35 "F.Fab" user "Ref Des/Assembly Top")
		(33 "B.Fab" user "Ref Des/Assembly Bottom")
	)
	(footprint ""
		(layer "B.Cu")
		(at 270.1544 -69.596)
		(property "Reference" "PU7"
			(at -1.8034 4.85267 0)
			(unlocked yes)
			(layer "B.SilkS")
			(effects
				(font
					(size 0.7874 0.5842)
					(thickness 0.1524)
				)
				(justify left mirror)
			)
		)
		(property "Value" ""
			(at 0 0 0)
			(layer "B.Fab")
			(effects
				(font
					(size 1.27 1.27)
				)
				(justify mirror)
			)
		)
		(duplicate_pad_numbers_are_jumpers no)
		(fp_line
			(start -4.05003 -3.549904)
			(end -3.5052 -3.549904)
			(stroke
				(width 0.1524)
				(type default)
			)
			(layer "B.SilkS")
		)
		(fp_line
			(start -4.05003 -3.0226)
			(end -4.05003 -3.549904)
			(stroke
				(width 0.1524)
				(type default)
			)
			(layer "B.SilkS")
		)
		(fp_line
			(start -4.05003 3.549904)
			(end -4.05003 3.0226)
			(stroke
				(width 0.1524)
				(type default)
			)
			(layer "B.SilkS")
		)
		(fp_line
			(start -3.5052 3.549904)
			(end -4.05003 3.549904)
			(stroke
				(width 0.1524)
				(type default)
			)
			(layer "B.SilkS")
		)
		(fp_line
			(start -0.9906 -3.549904)
			(end -0.0254 -3.549904)
			(stroke
				(width 0.1524)
				(type default)
			)
			(layer "B.SilkS")
		)
		(fp_line
			(start -0.0254 3.549904)
			(end -0.9906 3.549904)
			(stroke
				(width 0.1524)
				(type default)
			)
			(layer "B.SilkS")
		)
		(fp_line
			(start 3.5052 -3.549904)
			(end 4.05003 -3.549904)
			(stroke
				(width 0.1524)
				(type default)
			)
			(layer "B.SilkS")
		)
		(fp_line
			(start 4.05003 -3.549904)
			(end 4.05003 -3.0226)
			(stroke
				(width 0.1524)
				(type default)
			)
			(layer "B.SilkS")
		)
		(fp_line
			(start 4.05003 3.0226)
			(end 4.05003 3.549904)
			(stroke
				(width 0.1524)
				(type default)
			)
			(layer "B.SilkS")
		)
		(fp_line
			(start 4.05003 3.549904)
			(end 3.5052 3.549904)
			(stroke
				(width 0.1524)
				(type default)
			)
			(layer "B.SilkS")
		)
		(fp_poly
			(pts
				(xy 4.886198 -4.246372) (xy 5.604764 -3.52806) (xy 4.527042 -3.168904)
			)
			(stroke
				(width 0)
				(type default)
			)
			(fill yes)
			(layer "B.SilkS")
		)
		(fp_line
			(start -4.05003 -3.549904)
			(end 4.05003 -3.549904)
			(stroke
				(width 0.1)
				(type default)
			)
			(layer "B.Fab")
		)
		(fp_line
			(start -4.05003 3.549904)
			(end -4.05003 -3.549904)
			(stroke
				(width 0.1)
				(type default)
			)
			(layer "B.Fab")
		)
		(fp_line
			(start 4.05003 -3.549904)
			(end 4.05003 3.549904)
			(stroke
				(width 0.1)
				(type default)
			)
			(layer "B.Fab")
		)
		(fp_line
			(start 4.05003 3.549904)
			(end -4.05003 3.549904)
			(stroke
				(width 0.1)
				(type default)
			)
			(layer "B.Fab")
		)
		(fp_poly
			(pts
				(xy 5.588 -3.25882) (xy 5.588 -2.24282) (xy 4.572 -2.75082)
			)
			(stroke
				(width 0)
				(type default)
			)
			(fill yes)
			(layer "B.Fab")
		)
		(pad "1" smd oval
			(at 3.9497 -2.75082 270)
			(size 0.3048 0.8382)
			(layers "B.Cu" "B.Mask" "B.Paste")
			(net "P52V_HS1_ISET")
		)
		(pad "2" smd oval
			(at 3.9497 -2.25044 270)
			(size 0.3048 0.8382)
			(layers "B.Cu" "B.Mask" "B.Paste")
			(net "P52V_HS1_ISTART")
		)
		(pad "3" smd oval
			(at 3.9497 -1.75006 270)
			(size 0.3048 0.8382)
			(layers "B.Cu" "B.Mask" "B.Paste")
			(net "P52V_HS1_VCAP")
		)
		(pad "4" smd oval
			(at 3.9497 -1.24968 270)
			(size 0.3048 0.8382)
			(layers "B.Cu" "B.Mask" "B.Paste")
			(net "P52V_HS1_ESTART_R")
		)
		(pad "5" smd oval
			(at 3.9497 -0.7493 270)
			(size 0.3048 0.8382)
			(layers "B.Cu" "B.Mask" "B.Paste")
			(net "P52V_HS1_EFAULT_R")
		)
		(pad "6" smd oval
			(at 3.9497 -0.24892 270)
			(size 0.3048 0.8382)
			(layers "B.Cu" "B.Mask" "B.Paste")
			(net "P52V_HS1_EN")
		)
		(pad "7" smd oval
			(at 3.9497 0.24892 270)
			(size 0.3048 0.8382)
			(layers "B.Cu" "B.Mask" "B.Paste")
			(net "P52V_HS1_ADR0")
		)
		(pad "8" smd oval
			(at 3.9497 0.7493 270)
			(size 0.3048 0.8382)
			(layers "B.Cu" "B.Mask" "B.Paste")
			(net "P52V_HS1_ADR1")
		)
		(pad "9" smd oval
			(at 3.9497 1.24968 270)
			(size 0.3048 0.8382)
			(layers "B.Cu" "B.Mask" "B.Paste")
			(net "SMB_P52V_PDB_SCL_R1")
		)
		(pad "10" smd oval
			(at 3.9497 1.75006 270)
			(size 0.3048 0.8382)
			(layers "B.Cu" "B.Mask" "B.Paste")
			(net "SMB_CM_HS1_3V3SB_DATI")
		)
		(pad "11" smd oval
			(at 3.9497 2.25044 270)
			(size 0.3048 0.8382)
			(layers "B.Cu" "B.Mask" "B.Paste")
			(net "SMB_CM_HS1_3V3SB_DATO")
		)
		(pad "12" smd oval
			(at 3.9497 2.75082 270)
			(size 0.3048 0.8382)
			(layers "B.Cu" "B.Mask" "B.Paste")
			(net "P52V_HS1_MCB")
		)
		(pad "13" smd oval
			(at 3.2512 3.44932 180)
			(size 0.3048 0.8382)
			(layers "B.Cu" "B.Mask" "B.Paste")
			(net "P52V_HS1_GPO2")
		)
		(pad "14" smd oval
			(at 2.75082 3.44932 180)
			(size 0.3048 0.8382)
			(layers "B.Cu" "B.Mask" "B.Paste")
			(net "P52V_HS1_GPO1")
		)
		(pad "15" smd oval
			(at 2.25044 3.44932 180)
			(size 0.3048 0.8382)
			(layers "B.Cu" "B.Mask" "B.Paste")
			(net "Net_409")
		)
		(pad "16" smd oval
			(at 1.75006 3.44932 180)
			(size 0.3048 0.8382)
			(layers "B.Cu" "B.Mask" "B.Paste")
			(net "Net_408")
		)
		(pad "17" smd oval
			(at 1.24968 3.44932 180)
			(size 0.3048 0.8382)
			(layers "B.Cu" "B.Mask" "B.Paste")
			(net "PWRGD_P52V_HS1_PG")
		)
		(pad "18" smd oval
			(at 0.7493 3.44932 180)
			(size 0.3048 0.8382)
			(layers "B.Cu" "B.Mask" "B.Paste")
			(net "P52V_HS1_PWRGIN")
		)
		(pad "19" smd oval
			(at 0.24892 3.44932 180)
			(size 0.3048 0.8382)
			(layers "B.Cu" "B.Mask" "B.Paste")
			(net "GND_FIELD_SIGNAL")
		)
		(pad "20" smd oval
			(at -1.24968 3.44932 180)
			(size 0.3048 0.8382)
			(layers "B.Cu" "B.Mask" "B.Paste")
			(net "P52V_HS1_VCC")
		)
		(pad "21" smd oval
			(at -1.75006 3.44932 180)
			(size 0.3048 0.8382)
			(layers "B.Cu" "B.Mask" "B.Paste")
			(net "P52V_HS1_VCC")
		)
		(pad "22" smd oval
			(at -2.25044 3.44932 180)
			(size 0.3048 0.8382)
			(layers "B.Cu" "B.Mask" "B.Paste")
			(net "P52V_HS1_VCC")
		)
		(pad "23" smd oval
			(at -2.75082 3.44932 180)
			(size 0.3048 0.8382)
			(layers "B.Cu" "B.Mask" "B.Paste")
			(net "P52V_HS1_VCC")
		)
		(pad "24" smd oval
			(at -3.2512 3.44932 180)
			(size 0.3048 0.8382)
			(layers "B.Cu" "B.Mask" "B.Paste")
			(net "P52V_HS1_VCC")
		)
		(pad "25" smd oval
			(at -3.9497 2.75082 270)
			(size 0.3048 0.8382)
			(layers "B.Cu" "B.Mask" "B.Paste")
			(net "Net_16")
		)
		(pad "26" smd oval
			(at -3.9497 2.25044 270)
			(size 0.3048 0.8382)
			(layers "B.Cu" "B.Mask" "B.Paste")
			(net "Net_8")
		)
		(pad "27" smd oval
			(at -3.9497 1.75006 270)
			(size 0.3048 0.8382)
			(layers "B.Cu" "B.Mask" "B.Paste")
			(net "Net_15")
		)
		(pad "28" smd oval
			(at -3.9497 1.24968 270)
			(size 0.3048 0.8382)
			(layers "B.Cu" "B.Mask" "B.Paste")
			(net "Net_18")
		)
		(pad "29" smd oval
			(at -3.9497 0.7493 270)
			(size 0.3048 0.8382)
			(layers "B.Cu" "B.Mask" "B.Paste")
			(net "P52V_HS1_VCP")
		)
		(pad "30" smd oval
			(at -3.9497 0.24892 270)
			(size 0.3048 0.8382)
			(layers "B.Cu" "B.Mask" "B.Paste")
			(net "P52V_HS1_DV_DT_R")
		)
		(pad "31" smd oval
			(at -3.9497 -0.24892 270)
			(size 0.3048 0.8382)
			(layers "B.Cu" "B.Mask" "B.Paste")
			(net "P52V_HS1")
		)
		(pad "32" smd oval
			(at -3.9497 -0.7493 270)
			(size 0.3048 0.8382)
			(layers "B.Cu" "B.Mask" "B.Paste")
			(net "P52V_HS1_1272_GATE")
		)
		(pad "33" smd oval
			(at -3.9497 -1.24968 270)
			(size 0.3048 0.8382)
			(layers "B.Cu" "B.Mask" "B.Paste")
			(net "Net_21")
		)
		(pad "34" smd oval
			(at -3.9497 -1.75006 270)
			(size 0.3048 0.8382)
			(layers "B.Cu" "B.Mask" "B.Paste")
			(net "Net_20")
		)
		(pad "35" smd oval
			(at -3.9497 -2.25044 270)
			(size 0.3048 0.8382)
			(layers "B.Cu" "B.Mask" "B.Paste")
			(net "Net_4")
		)
		(pad "36" smd oval
			(at -3.9497 -2.75082 270)
			(size 0.3048 0.8382)
			(layers "B.Cu" "B.Mask" "B.Paste")
			(net "Net_17")
		)
		(pad "37" smd oval
			(at -3.2512 -3.44932 180)
			(size 0.3048 0.8382)
			(layers "B.Cu" "B.Mask" "B.Paste")
			(net "Net_13")
		)
		(pad "38" smd oval
			(at -2.75082 -3.44932 180)
			(size 0.3048 0.8382)
			(layers "B.Cu" "B.Mask" "B.Paste")
			(net "P52V_HS_1272_S_N")
		)
		(pad "39" smd oval
			(at -2.25044 -3.44932 180)
			(size 0.3048 0.8382)
			(layers "B.Cu" "B.Mask" "B.Paste")
			(net "P52V_HS_1272_S_P")
		)
		(pad "40" smd oval
			(at -1.75006 -3.44932 180)
			(size 0.3048 0.8382)
			(layers "B.Cu" "B.Mask" "B.Paste")
			(net "Net_12")
		)
		(pad "41" smd oval
			(at -1.24968 -3.44932 180)
			(size 0.3048 0.8382)
			(layers "B.Cu" "B.Mask" "B.Paste")
			(net "P52V_HS1_VCC")
		)
		(pad "42" smd oval
			(at 0.24892 -3.44932 180)
			(size 0.3048 0.8382)
			(layers "B.Cu" "B.Mask" "B.Paste")
			(net "P52V_HS1_VREG")
		)
		(pad "43" smd oval
			(at 0.7493 -3.44932 180)
			(size 0.3048 0.8382)
			(layers "B.Cu" "B.Mask" "B.Paste")
			(net "P52V_HS1_TEMPN")
		)
		(pad "44" smd oval
			(at 1.24968 -3.44932 180)
			(size 0.3048 0.8382)
			(layers "B.Cu" "B.Mask" "B.Paste")
			(net "P52V_HS1_TEMPP")
		)
		(pad "45" smd oval
			(at 1.75006 -3.44932 180)
			(size 0.3048 0.8382)
			(layers "B.Cu" "B.Mask" "B.Paste")
			(net "P52V_HS1_UVH")
		)
		(pad "46" smd oval
			(at 2.25044 -3.44932 180)
			(size 0.3048 0.8382)
			(layers "B.Cu" "B.Mask" "B.Paste")
			(net "P52V_HS1_UVLO_EN")
		)
		(pad "47" smd oval
			(at 2.75082 -3.44932 180)
			(size 0.3048 0.8382)
			(layers "B.Cu" "B.Mask" "B.Paste")
			(net "P52V_HS1_OV")
		)
		(pad "48" smd oval
			(at 3.2512 -3.44932 180)
			(size 0.3048 0.8382)
			(layers "B.Cu" "B.Mask" "B.Paste")
			(net "P52V_HS1_RND")
		)
		(pad "PAD1" smd rect
			(at 1.89738 0 180)
			(size 2.794 5.588)
			(layers "B.Cu" "B.Mask" "B.Paste")
			(net "GND_FIELD_SIGNAL")
		)
		(pad "PAD2" smd rect
			(at -1.55194 0 180)
			(size 1.4986 3.4036)
			(layers "B.Cu" "B.Mask" "B.Paste")
			(net "P52V_HS1_VCC")
		)
		(zone
			(layer "B.Cu")
			(hatch none 0.5)
			(connect_pads
				(clearance 0)
			)
			(min_thickness 0.25)
			(keepout
				(tracks not_allowed)
				(vias allowed)
				(pads allowed)
				(copperpour not_allowed)
				(footprints allowed)
			)
			(placement
				(enabled no)
				(sheetname "")
			)
			(fill
				(thermal_gap 0.5)
				(thermal_bridge_width 0.5)
				(island_removal_mode 0)
			)
			(polygon
				(pts
					(xy 266.6746 -72.5678) (xy 266.6746 -66.6242) (xy 269.3924 -66.6242) (xy 269.3924 -67.8434) (xy 267.7922 -67.8434)
					(xy 267.7922 -71.3486) (xy 269.3924 -71.3486) (xy 269.3924 -72.5678)
				)
			)
		)
		(zone
			(layer "B.Cu")
			(hatch none 0.5)
			(connect_pads
				(clearance 0)
			)
			(min_thickness 0.25)
			(keepout
				(tracks not_allowed)
				(vias allowed)
				(pads allowed)
				(copperpour not_allowed)
				(footprints allowed)
			)
			(placement
				(enabled no)
				(sheetname "")
			)
			(fill
				(thermal_gap 0.5)
				(thermal_bridge_width 0.5)
				(island_removal_mode 0)
			)
			(polygon
				(pts
					(xy 273.6342 -70.9168) (xy 273.6342 -66.6242) (xy 269.4178 -66.6242) (xy 269.4178 -72.5678) (xy 273.6342 -72.5678)
					(xy 273.6342 -70.9422) (xy 273.5072 -70.9422) (xy 273.5072 -72.4408) (xy 270.5862 -72.4408) (xy 270.5862 -66.7512)
					(xy 273.5072 -66.7512) (xy 273.5072 -70.9168)
				)
			)
		)
	)
	(footprint ""
		(layer "B.Cu")
		(at 289.5854 -62.992 90)
		(property "Reference" "PR214"
			(at 0 0 90)
			(layer "B.SilkS")
			(hide yes)
			(effects
				(font
					(size 1.27 1.27)
				)
				(justify mirror)
			)
		)
		(property "Value" ""
			(at 0 0 90)
			(layer "B.Fab")
			(effects
				(font
					(size 1.27 1.27)
				)
				(justify mirror)
			)
		)
		(duplicate_pad_numbers_are_jumpers no)
		(fp_line
			(start 0.7874 -0.4064)
			(end -0.7874 -0.4064)
			(stroke
				(width 0.1524)
				(type default)
			)
			(layer "B.SilkS")
		)
		(fp_line
			(start -0.7874 -0.4064)
			(end -0.7874 0.4064)
			(stroke
				(width 0.1524)
				(type default)
			)
			(layer "B.SilkS")
		)
		(fp_line
			(start 0.7874 0.4064)
			(end 0.7874 -0.4064)
			(stroke
				(width 0.1524)
				(type default)
			)
			(layer "B.SilkS")
		)
		(fp_line
			(start -0.7874 0.4064)
			(end 0.7874 0.4064)
			(stroke
				(width 0.1524)
				(type default)
			)
			(layer "B.SilkS")
		)
		(fp_line
			(start 0.67945 -0.305054)
			(end 0.12065 -0.305054)
			(stroke
				(width 0.1)
				(type default)
			)
			(layer "B.Fab")
		)
		(fp_line
			(start 0.12065 -0.305054)
			(end 0.12065 -0.2794)
			(stroke
				(width 0.1)
				(type default)
			)
			(layer "B.Fab")
		)
		(fp_line
			(start -0.12065 -0.3048)
			(end -0.67945 -0.3048)
			(stroke
				(width 0.1)
				(type default)
			)
			(layer "B.Fab")
		)
		(fp_line
			(start -0.67945 -0.3048)
			(end -0.67945 0.3048)
			(stroke
				(width 0.1)
				(type default)
			)
			(layer "B.Fab")
		)
		(fp_line
			(start 0.12065 -0.2794)
			(end -0.12065 -0.2794)
			(stroke
				(width 0.1)
				(type default)
			)
			(layer "B.Fab")
		)
		(fp_line
			(start -0.12065 -0.2794)
			(end -0.12065 -0.3048)
			(stroke
				(width 0.1)
				(type default)
			)
			(layer "B.Fab")
		)
		(fp_line
			(start 0.12065 0.2794)
			(end 0.12065 0.3048)
			(stroke
				(width 0.1)
				(type default)
			)
			(layer "B.Fab")
		)
		(fp_line
			(start -0.120396 0.2794)
			(end 0.12065 0.2794)
			(stroke
				(width 0.1)
				(type default)
			)
			(layer "B.Fab")
		)
		(fp_line
			(start 0.67945 0.3048)
			(end 0.67945 -0.305054)
			(stroke
				(width 0.1)
				(type default)
			)
			(layer "B.Fab")
		)
		(fp_line
			(start 0.12065 0.3048)
			(end 0.67945 0.3048)
			(stroke
				(width 0.1)
				(type default)
			)
			(layer "B.Fab")
		)
		(fp_line
			(start -0.120396 0.3048)
			(end -0.120396 0.2794)
			(stroke
				(width 0.1)
				(type default)
			)
			(layer "B.Fab")
		)
		(fp_line
			(start -0.67945 0.3048)
			(end -0.120396 0.3048)
			(stroke
				(width 0.1)
				(type default)
			)
			(layer "B.Fab")
		)
		(pad "1" smd circle
			(at 0.40005 0 270)
			(size 0 0)
			(layers "B.Cu" "B.Mask" "B.Paste")
			(net "P52V_HS1_MODE")
		)
		(pad "2" smd circle
			(at -0.40005 0 270)
			(size 0 0)
			(layers "B.Cu" "B.Mask" "B.Paste")
			(net "P52V_HS1_INTVCC")
		)
	)
	(footprint ""
		(layer "B.Cu")
		(at 256.798318 -144.790668 90)
		(property "Reference" "J14"
			(at 1.259332 -5.745988 270)
			(unlocked yes)
			(layer "B.SilkS")
			(effects
				(font
					(size 0.7874 0.5842)
					(thickness 0.1524)
				)
				(justify left mirror)
			)
		)
		(property "Value" ""
			(at 0 0 90)
			(layer "B.Fab")
			(effects
				(font
					(size 1.27 1.27)
				)
				(justify mirror)
			)
		)
		(duplicate_pad_numbers_are_jumpers no)
		(fp_line
			(start 3.330702 -4.771136)
			(end -3.330702 -4.771136)
			(stroke
				(width 0.1524)
				(type default)
			)
			(layer "B.SilkS")
		)
		(fp_line
			(start -3.330702 -4.771136)
			(end 0 4.011168)
			(stroke
				(width 0.1524)
				(type default)
			)
			(layer "B.SilkS")
		)
		(fp_line
			(start 0 4.011168)
			(end 3.330702 -4.771136)
			(stroke
				(width 0.1524)
				(type default)
			)
			(layer "B.SilkS")
		)
		(fp_line
			(start 3.330702 -4.771136)
			(end -3.330702 -4.771136)
			(stroke
				(width 0.1)
				(type default)
			)
			(layer "B.Fab")
		)
		(fp_line
			(start -3.330702 -4.771136)
			(end 0 4.011168)
			(stroke
				(width 0.1)
				(type default)
			)
			(layer "B.Fab")
		)
		(fp_line
			(start 0 4.011168)
			(end 3.330702 -4.771136)
			(stroke
				(width 0.1)
				(type default)
			)
			(layer "B.Fab")
		)
		(pad "1" thru_hole circle
			(at 0 0 270)
			(size 2.159 2.159)
			(drill 1.7018)
			(layers "*.Cu" "*.Mask")
			(remove_unused_layers no)
			(net "GND3")
			(clearance 0.0254)
			(thermal_gap 0.0254)
		)
		(pad "2" thru_hole circle
			(at 1.27 -3.348736 270)
			(size 2.159 2.159)
			(drill 1.7018)
			(layers "*.Cu" "*.Mask")
			(remove_unused_layers no)
			(net "TDR_SE_50_OHM_BOT")
			(clearance 0.0254)
			(thermal_gap 0.0254)
		)
		(pad "3" thru_hole circle
			(at -1.27 -3.348736 270)
			(size 2.159 2.159)
			(drill 1.7018)
			(layers "*.Cu" "*.Mask")
			(remove_unused_layers no)
			(net "TDR_SE_50_OHM_BOT")
			(clearance 0.0254)
			(thermal_gap 0.0254)
		)
	)
)
